(kicad_pcb
	(version 20260206)
	(generator "pcbnew")
	(generator_version "10.0")
	(general
		(thickness 1.6)
		(legacy_teardrops no)
	)
	(paper "A4")
	(title_block
		(title "Wiwynn_Tioga_Pass_MB.brd")
		(comment 1 "Tioga Pass / footprints 652-658 of 4770")
	)
	(layers
		(0 "F.Cu" signal "TOP")
		(4 "In1.Cu" signal "L2GND")
		(6 "In2.Cu" signal "L3")
		(8 "In3.Cu" signal "L4GND")
		(10 "In4.Cu" signal "L5")
		(12 "In5.Cu" signal "L6GND")
		(14 "In6.Cu" signal "L7VCC")
		(16 "In7.Cu" signal "L8VCC")
		(18 "In8.Cu" signal "L9GND")
		(20 "In9.Cu" signal "L10")
		(22 "In10.Cu" signal "L11GND")
		(24 "In11.Cu" signal "L12")
		(26 "In12.Cu" signal "L13GND")
		(2 "B.Cu" signal "BOTTOM")
		(9 "F.Adhes" user "F.Adhesive")
		(11 "B.Adhes" user "B.Adhesive")
		(13 "F.Paste" user "Package Geometry/Pastemask Top")
		(15 "B.Paste" user "Package Geometry/Pastemask Bottom")
		(5 "F.SilkS" user "Ref Des/Silkscreen Top")
		(7 "B.SilkS" user "Ref Des/Silkscreen Bottom")
		(1 "F.Mask" user "Board Geometry/Soldermask Top")
		(3 "B.Mask" user "Board Geometry/Soldermask Bottom")
		(17 "Dwgs.User" user "User.Drawings")
		(19 "Cmts.User" user "User.Comments")
		(21 "Eco1.User" user "User.Eco1")
		(23 "Eco2.User" user "User.Eco2")
		(25 "Edge.Cuts" user "Board Geometry/Outline")
		(27 "Margin" user)
		(31 "F.CrtYd" user "Package Geometry/Place Bound Top")
		(29 "B.CrtYd" user "Package Geometry/Place Bound Bottom")
		(35 "F.Fab" user "Ref Des/Assembly Top")
		(33 "B.Fab" user "Ref Des/Assembly Bottom")
	)
	(footprint ""
		(layer "F.Cu")
		(at 410.806138 -107.146598 90)
		(property "Reference" "R8C14"
			(at 0 0 90)
			(layer "F.SilkS")
			(hide yes)
			(effects
				(font
					(size 1.27 1.27)
				)
			)
		)
		(property "Value" ""
			(at 0 0 90)
			(layer "F.Fab")
			(effects
				(font
					(size 1.27 1.27)
				)
			)
		)
		(duplicate_pad_numbers_are_jumpers no)
		(fp_poly
			(pts
				(xy -0.2794 -0.1016) (xy 0.2794 -0.1016) (xy 0.2794 0.9906) (xy -0.2794 0.9906)
			)
			(stroke
				(width 0)
				(type default)
			)
			(fill no)
			(layer "F.CrtYd")
		)
		(fp_line
			(start 0.2794 -0.1016)
			(end -0.2794 -0.1016)
			(stroke
				(width 0.1)
				(type default)
			)
			(layer "F.Fab")
		)
		(fp_line
			(start -0.2794 -0.1016)
			(end -0.2794 0.9906)
			(stroke
				(width 0.1)
				(type default)
			)
			(layer "F.Fab")
		)
		(fp_line
			(start 0.2794 0.9906)
			(end 0.2794 -0.1016)
			(stroke
				(width 0.1)
				(type default)
			)
			(layer "F.Fab")
		)
		(fp_line
			(start -0.2794 0.9906)
			(end 0.2794 0.9906)
			(stroke
				(width 0.1)
				(type default)
			)
			(layer "F.Fab")
		)
		(pad "1" smd rect
			(at 0 0 90)
			(size 0.508 0.508)
			(layers "F.Cu" "F.Mask" "F.Paste")
			(net "SMB_HOST_STBY_LVC3_SCL_R1")
		)
		(pad "2" smd rect
			(at 0 0.889 90)
			(size 0.508 0.508)
			(layers "F.Cu" "F.Mask" "F.Paste")
			(net "SMB_HOST_STBY_LVC3_SCL")
		)
		(zone
			(layer "F.Cu")
			(hatch none 0.5)
			(connect_pads
				(clearance 0)
			)
			(min_thickness 0.25)
			(keepout
				(tracks allowed)
				(vias not_allowed)
				(pads allowed)
				(copperpour not_allowed)
				(footprints allowed)
			)
			(placement
				(enabled no)
				(sheetname "")
			)
			(fill
				(thermal_gap 0.5)
				(thermal_bridge_width 0.5)
				(island_removal_mode 0)
			)
			(polygon
				(pts
					(xy 411.060138 -106.892598) (xy 411.060138 -107.400598) (xy 411.441138 -107.400598) (xy 411.441138 -106.892598)
				)
			)
		)
		(zone
			(layer "F.Cu")
			(hatch none 0.5)
			(connect_pads
				(clearance 0)
			)
			(min_thickness 0.25)
			(keepout
				(tracks not_allowed)
				(vias allowed)
				(pads allowed)
				(copperpour not_allowed)
				(footprints allowed)
			)
			(placement
				(enabled no)
				(sheetname "")
			)
			(fill
				(thermal_gap 0.5)
				(thermal_bridge_width 0.5)
				(island_removal_mode 0)
			)
			(polygon
				(pts
					(xy 411.441138 -106.892598) (xy 411.441138 -107.400598) (xy 411.060138 -107.400598) (xy 411.060138 -106.892598)
				)
			)
		)
	)
	(footprint ""
		(layer "F.Cu")
		(at 109.728 -69.85)
		(property "Reference" "R3D22"
			(at 0 0 0)
			(layer "F.SilkS")
			(hide yes)
			(effects
				(font
					(size 1.27 1.27)
				)
			)
		)
		(property "Value" ""
			(at 0 0 0)
			(layer "F.Fab")
			(effects
				(font
					(size 1.27 1.27)
				)
			)
		)
		(duplicate_pad_numbers_are_jumpers no)
		(fp_poly
			(pts
				(xy -0.2794 -0.1016) (xy 0.2794 -0.1016) (xy 0.2794 0.9906) (xy -0.2794 0.9906)
			)
			(stroke
				(width 0)
				(type default)
			)
			(fill no)
			(layer "F.CrtYd")
		)
		(fp_line
			(start -0.2794 -0.1016)
			(end -0.2794 0.9906)
			(stroke
				(width 0.1)
				(type default)
			)
			(layer "F.Fab")
		)
		(fp_line
			(start -0.2794 0.9906)
			(end 0.2794 0.9906)
			(stroke
				(width 0.1)
				(type default)
			)
			(layer "F.Fab")
		)
		(fp_line
			(start 0.2794 -0.1016)
			(end -0.2794 -0.1016)
			(stroke
				(width 0.1)
				(type default)
			)
			(layer "F.Fab")
		)
		(fp_line
			(start 0.2794 0.9906)
			(end 0.2794 -0.1016)
			(stroke
				(width 0.1)
				(type default)
			)
			(layer "F.Fab")
		)
		(pad "1" smd rect
			(at 0 0)
			(size 0.508 0.508)
			(layers "F.Cu" "F.Mask" "F.Paste")
			(net "PVCCIO_CPU1")
		)
		(pad "2" smd rect
			(at 0 0.889)
			(size 0.508 0.508)
			(layers "F.Cu" "F.Mask" "F.Paste")
			(net "PU_CPU1_FRMAGENT")
		)
		(zone
			(layer "F.Cu")
			(hatch none 0.5)
			(connect_pads
				(clearance 0)
			)
			(min_thickness 0.25)
			(keepout
				(tracks allowed)
				(vias not_allowed)
				(pads allowed)
				(copperpour not_allowed)
				(footprints allowed)
			)
			(placement
				(enabled no)
				(sheetname "")
			)
			(fill
				(thermal_gap 0.5)
				(thermal_bridge_width 0.5)
				(island_removal_mode 0)
			)
			(polygon
				(pts
					(xy 109.474 -69.596) (xy 109.982 -69.596) (xy 109.982 -69.215) (xy 109.474 -69.215)
				)
			)
		)
		(zone
			(layer "F.Cu")
			(hatch none 0.5)
			(connect_pads
				(clearance 0)
			)
			(min_thickness 0.25)
			(keepout
				(tracks not_allowed)
				(vias allowed)
				(pads allowed)
				(copperpour not_allowed)
				(footprints allowed)
			)
			(placement
				(enabled no)
				(sheetname "")
			)
			(fill
				(thermal_gap 0.5)
				(thermal_bridge_width 0.5)
				(island_removal_mode 0)
			)
			(polygon
				(pts
					(xy 109.474 -69.215) (xy 109.982 -69.215) (xy 109.982 -69.596) (xy 109.474 -69.596)
				)
			)
		)
	)
	(footprint ""
		(layer "F.Cu")
		(at 464.312 -128.4986 -90)
		(property "Reference" "C9B8"
			(at 0 0 270)
			(layer "F.SilkS")
			(hide yes)
			(effects
				(font
					(size 1.27 1.27)
				)
			)
		)
		(property "Value" ""
			(at 0 0 270)
			(layer "F.Fab")
			(effects
				(font
					(size 1.27 1.27)
				)
			)
		)
		(duplicate_pad_numbers_are_jumpers no)
		(fp_line
			(start -2.2987 7.3533)
			(end -1.7272 7.3533)
			(stroke
				(width 0.1524)
				(type default)
			)
			(layer "F.SilkS")
		)
		(fp_line
			(start 1.7272 7.3533)
			(end 2.2987 7.3533)
			(stroke
				(width 0.1524)
				(type default)
			)
			(layer "F.SilkS")
		)
		(fp_line
			(start 2.2987 7.3533)
			(end 2.2987 -0.2413)
			(stroke
				(width 0.1524)
				(type default)
			)
			(layer "F.SilkS")
		)
		(fp_line
			(start -2.032 1.524)
			(end -1.7272 1.524)
			(stroke
				(width 0.1524)
				(type default)
			)
			(layer "F.SilkS")
		)
		(fp_line
			(start 2.032 1.524)
			(end 1.7272 1.524)
			(stroke
				(width 0.1524)
				(type default)
			)
			(layer "F.SilkS")
		)
		(fp_line
			(start -2.2987 -0.2413)
			(end -2.2987 7.3533)
			(stroke
				(width 0.1524)
				(type default)
			)
			(layer "F.SilkS")
		)
		(fp_line
			(start -2.032 -0.2413)
			(end -2.2987 -0.2413)
			(stroke
				(width 0.1524)
				(type default)
			)
			(layer "F.SilkS")
		)
		(fp_line
			(start 2.2987 -0.2413)
			(end 2.032 -0.2413)
			(stroke
				(width 0.1524)
				(type default)
			)
			(layer "F.SilkS")
		)
		(fp_line
			(start -2.032 -1.524)
			(end -2.032 1.524)
			(stroke
				(width 0.1524)
				(type default)
			)
			(layer "F.SilkS")
		)
		(fp_line
			(start -1.7272 -1.524)
			(end -2.032 -1.524)
			(stroke
				(width 0.1524)
				(type default)
			)
			(layer "F.SilkS")
		)
		(fp_line
			(start 1.7272 -1.524)
			(end 2.032 -1.524)
			(stroke
				(width 0.1524)
				(type default)
			)
			(layer "F.SilkS")
		)
		(fp_line
			(start 2.032 -1.524)
			(end 2.032 1.524)
			(stroke
				(width 0.1524)
				(type default)
			)
			(layer "F.SilkS")
		)
		(fp_poly
			(pts
				(xy -2.2987 -0.2413) (xy 2.2987 -0.2413) (xy 2.2987 7.3533) (xy -2.2987 7.3533)
			)
			(stroke
				(width 0)
				(type default)
			)
			(fill no)
			(layer "F.CrtYd")
		)
		(fp_line
			(start -2.2987 7.3533)
			(end -2.2987 -0.2413)
			(stroke
				(width 0.1)
				(type default)
			)
			(layer "F.Fab")
		)
		(fp_line
			(start 2.2987 7.3533)
			(end -2.2987 7.3533)
			(stroke
				(width 0.1)
				(type default)
			)
			(layer "F.Fab")
		)
		(fp_line
			(start -2.2987 -0.2413)
			(end 2.2987 -0.2413)
			(stroke
				(width 0.1)
				(type default)
			)
			(layer "F.Fab")
		)
		(fp_line
			(start 2.2987 -0.2413)
			(end 2.2987 7.3533)
			(stroke
				(width 0.1)
				(type default)
			)
			(layer "F.Fab")
		)
		(pad "1" smd rect
			(at 0 0 270)
			(size 2.54 3.048)
			(layers "F.Cu" "F.Mask" "F.Paste")
			(net "P5V_USB")
		)
		(pad "2" smd rect
			(at 0 7.112 270)
			(size 2.54 3.048)
			(layers "F.Cu" "F.Mask" "F.Paste")
			(net "GND")
		)
	)
	(footprint ""
		(layer "F.Cu")
		(at 178.943 -8.1788)
		(property "Reference" "C4G9"
			(at 0 0 0)
			(layer "F.SilkS")
			(hide yes)
			(effects
				(font
					(size 1.27 1.27)
				)
			)
		)
		(property "Value" ""
			(at 0 0 0)
			(layer "F.Fab")
			(effects
				(font
					(size 1.27 1.27)
				)
			)
		)
		(duplicate_pad_numbers_are_jumpers no)
		(fp_rect
			(start -0.3048 0.9906)
			(end 0.3048 -0.1016)
			(stroke
				(width 0)
				(type default)
			)
			(fill no)
			(layer "F.CrtYd")
		)
		(fp_line
			(start -0.3048 -0.1016)
			(end -0.3048 0.9906)
			(stroke
				(width 0.1)
				(type default)
			)
			(layer "F.Fab")
		)
		(fp_line
			(start -0.3048 0.9906)
			(end 0.3048 0.9906)
			(stroke
				(width 0.1)
				(type default)
			)
			(layer "F.Fab")
		)
		(fp_line
			(start 0.3048 -0.1016)
			(end -0.3048 -0.1016)
			(stroke
				(width 0.1)
				(type default)
			)
			(layer "F.Fab")
		)
		(fp_line
			(start 0.3048 0.9906)
			(end 0.3048 -0.1016)
			(stroke
				(width 0.1)
				(type default)
			)
			(layer "F.Fab")
		)
		(pad "1" smd rect
			(at 0 0)
			(size 0.508 0.508)
			(layers "F.Cu" "F.Mask" "F.Paste")
			(net "PWRGD_PVPP_GHJ_R")
		)
		(pad "2" smd rect
			(at 0 0.889)
			(size 0.508 0.508)
			(layers "F.Cu" "F.Mask" "F.Paste")
			(net "GND")
		)
		(zone
			(layer "F.Cu")
			(hatch none 0.5)
			(connect_pads
				(clearance 0)
			)
			(min_thickness 0.25)
			(keepout
				(tracks allowed)
				(vias not_allowed)
				(pads allowed)
				(copperpour not_allowed)
				(footprints allowed)
			)
			(placement
				(enabled no)
				(sheetname "")
			)
			(fill
				(thermal_gap 0.5)
				(thermal_bridge_width 0.5)
				(island_removal_mode 0)
			)
			(polygon
				(pts
					(xy 178.689 -7.5438) (xy 179.197 -7.5438) (xy 179.197 -7.9248) (xy 178.689 -7.9248)
				)
			)
		)
		(zone
			(layer "F.Cu")
			(hatch none 0.5)
			(connect_pads
				(clearance 0)
			)
			(min_thickness 0.25)
			(keepout
				(tracks not_allowed)
				(vias allowed)
				(pads allowed)
				(copperpour not_allowed)
				(footprints allowed)
			)
			(placement
				(enabled no)
				(sheetname "")
			)
			(fill
				(thermal_gap 0.5)
				(thermal_bridge_width 0.5)
				(island_removal_mode 0)
			)
			(polygon
				(pts
					(xy 178.689 -7.5438) (xy 179.197 -7.5438) (xy 179.197 -7.9248) (xy 178.689 -7.9248)
				)
			)
		)
	)
	(footprint ""
		(layer "F.Cu")
		(at 374.4849 -136.9949)
		(property "Reference" "C7A33"
			(at 0 0 0)
			(layer "F.SilkS")
			(hide yes)
			(effects
				(font
					(size 1.27 1.27)
				)
			)
		)
		(property "Value" ""
			(at 0 0 0)
			(layer "F.Fab")
			(effects
				(font
					(size 1.27 1.27)
				)
			)
		)
		(duplicate_pad_numbers_are_jumpers no)
		(fp_rect
			(start -0.7239 1.9939)
			(end 0.7239 -0.2159)
			(stroke
				(width 0)
				(type default)
			)
			(fill no)
			(layer "F.CrtYd")
		)
		(fp_line
			(start -0.7239 -0.2159)
			(end -0.7239 1.9939)
			(stroke
				(width 0.1)
				(type default)
			)
			(layer "F.Fab")
		)
		(fp_line
			(start -0.7239 1.9939)
			(end 0.7239 1.9939)
			(stroke
				(width 0.1)
				(type default)
			)
			(layer "F.Fab")
		)
		(fp_line
			(start 0.7239 -0.2159)
			(end -0.7239 -0.2159)
			(stroke
				(width 0.1)
				(type default)
			)
			(layer "F.Fab")
		)
		(fp_line
			(start 0.7239 1.9939)
			(end 0.7239 -0.2159)
			(stroke
				(width 0.1)
				(type default)
			)
			(layer "F.Fab")
		)
		(pad "1" smd rect
			(at 0 0)
			(size 1.27 1.016)
			(layers "F.Cu" "F.Mask" "F.Paste")
			(net "PVNN_PCH_STBY")
		)
		(pad "2" smd rect
			(at 0 1.778)
			(size 1.27 1.016)
			(layers "F.Cu" "F.Mask" "F.Paste")
			(net "GND")
		)
		(zone
			(layer "F.Cu")
			(hatch none 0.5)
			(connect_pads
				(clearance 0)
			)
			(min_thickness 0.25)
			(keepout
				(tracks not_allowed)
				(vias allowed)
				(pads allowed)
				(copperpour not_allowed)
				(footprints allowed)
			)
			(placement
				(enabled no)
				(sheetname "")
			)
			(fill
				(thermal_gap 0.5)
				(thermal_bridge_width 0.5)
				(island_removal_mode 0)
			)
			(polygon
				(pts
					(xy 373.8499 -135.7249) (xy 375.1199 -135.7249) (xy 375.1199 -136.4869) (xy 373.8499 -136.4869)
				)
			)
		)
	)
	(footprint ""
		(layer "F.Cu")
		(at 375.167144 -10.916158)
		(property "Reference" "C7G16"
			(at 0 0 0)
			(layer "F.SilkS")
			(hide yes)
			(effects
				(font
					(size 1.27 1.27)
				)
			)
		)
		(property "Value" ""
			(at 0 0 0)
			(layer "F.Fab")
			(effects
				(font
					(size 1.27 1.27)
				)
			)
		)
		(duplicate_pad_numbers_are_jumpers no)
		(fp_rect
			(start -0.3048 0.9906)
			(end 0.3048 -0.1016)
			(stroke
				(width 0)
				(type default)
			)
			(fill no)
			(layer "F.CrtYd")
		)
		(fp_line
			(start -0.3048 -0.1016)
			(end -0.3048 0.9906)
			(stroke
				(width 0.1)
				(type default)
			)
			(layer "F.Fab")
		)
		(fp_line
			(start -0.3048 0.9906)
			(end 0.3048 0.9906)
			(stroke
				(width 0.1)
				(type default)
			)
			(layer "F.Fab")
		)
		(fp_line
			(start 0.3048 -0.1016)
			(end -0.3048 -0.1016)
			(stroke
				(width 0.1)
				(type default)
			)
			(layer "F.Fab")
		)
		(fp_line
			(start 0.3048 0.9906)
			(end 0.3048 -0.1016)
			(stroke
				(width 0.1)
				(type default)
			)
			(layer "F.Fab")
		)
		(pad "1" smd rect
			(at 0 0)
			(size 0.508 0.508)
			(layers "F.Cu" "F.Mask" "F.Paste")
			(net "P3E_CPU0_PE2_SS_TXN<10>")
		)
		(pad "2" smd rect
			(at 0 0.889)
			(size 0.508 0.508)
			(layers "F.Cu" "F.Mask" "F.Paste")
			(net "P3E_CPU0_PE2_SS_C_TXN<10>")
		)
		(zone
			(layer "F.Cu")
			(hatch none 0.5)
			(connect_pads
				(clearance 0)
			)
			(min_thickness 0.25)
			(keepout
				(tracks allowed)
				(vias not_allowed)
				(pads allowed)
				(copperpour not_allowed)
				(footprints allowed)
			)
			(placement
				(enabled no)
				(sheetname "")
			)
			(fill
				(thermal_gap 0.5)
				(thermal_bridge_width 0.5)
				(island_removal_mode 0)
			)
			(polygon
				(pts
					(xy 374.913144 -10.281158) (xy 375.421144 -10.281158) (xy 375.421144 -10.662158) (xy 374.913144 -10.662158)
				)
			)
		)
		(zone
			(layer "F.Cu")
			(hatch none 0.5)
			(connect_pads
				(clearance 0)
			)
			(min_thickness 0.25)
			(keepout
				(tracks not_allowed)
				(vias allowed)
				(pads allowed)
				(copperpour not_allowed)
				(footprints allowed)
			)
			(placement
				(enabled no)
				(sheetname "")
			)
			(fill
				(thermal_gap 0.5)
				(thermal_bridge_width 0.5)
				(island_removal_mode 0)
			)
			(polygon
				(pts
					(xy 374.913144 -10.281158) (xy 375.421144 -10.281158) (xy 375.421144 -10.662158) (xy 374.913144 -10.662158)
				)
			)
		)
	)
	(footprint ""
		(layer "F.Cu")
		(at 30.579568 -3.321812 90)
		(property "Reference" "C1G19"
			(at 0 0 90)
			(layer "F.SilkS")
			(hide yes)
			(effects
				(font
					(size 1.27 1.27)
				)
			)
		)
		(property "Value" ""
			(at 0 0 90)
			(layer "F.Fab")
			(effects
				(font
					(size 1.27 1.27)
				)
			)
		)
		(duplicate_pad_numbers_are_jumpers no)
		(fp_poly
			(pts
				(xy 0.3048 -0.1016) (xy 0.3048 0.9906) (xy -0.3048 0.9906) (xy -0.3048 -0.1016)
			)
			(stroke
				(width 0)
				(type default)
			)
			(fill no)
			(layer "F.CrtYd")
		)
		(fp_line
			(start 0.3048 -0.1016)
			(end -0.3048 -0.1016)
			(stroke
				(width 0.1)
				(type default)
			)
			(layer "F.Fab")
		)
		(fp_line
			(start -0.3048 -0.1016)
			(end -0.3048 0.9906)
			(stroke
				(width 0.1)
				(type default)
			)
			(layer "F.Fab")
		)
		(fp_line
			(start 0.3048 0.9906)
			(end 0.3048 -0.1016)
			(stroke
				(width 0.1)
				(type default)
			)
			(layer "F.Fab")
		)
		(fp_line
			(start -0.3048 0.9906)
			(end 0.3048 0.9906)
			(stroke
				(width 0.1)
				(type default)
			)
			(layer "F.Fab")
		)
		(pad "1" smd rect
			(at 0 0 90)
			(size 0.508 0.508)
			(layers "F.Cu" "F.Mask" "F.Paste")
			(net "M_J_VREF")
		)
		(pad "2" smd rect
			(at 0 0.889 90)
			(size 0.508 0.508)
			(layers "F.Cu" "F.Mask" "F.Paste")
			(net "GND")
		)
		(zone
			(layer "F.Cu")
			(hatch none 0.5)
			(connect_pads
				(clearance 0)
			)
			(min_thickness 0.25)
			(keepout
				(tracks allowed)
				(vias not_allowed)
				(pads allowed)
				(copperpour not_allowed)
				(footprints allowed)
			)
			(placement
				(enabled no)
				(sheetname "")
			)
			(fill
				(thermal_gap 0.5)
				(thermal_bridge_width 0.5)
				(island_removal_mode 0)
			)
			(polygon
				(pts
					(xy 30.833568 -3.067812) (xy 30.833568 -3.575812) (xy 31.214568 -3.575812) (xy 31.214568 -3.067812)
				)
			)
		)
		(zone
			(layer "F.Cu")
			(hatch none 0.5)
			(connect_pads
				(clearance 0)
			)
			(min_thickness 0.25)
			(keepout
				(tracks not_allowed)
				(vias allowed)
				(pads allowed)
				(copperpour not_allowed)
				(footprints allowed)
			)
			(placement
				(enabled no)
				(sheetname "")
			)
			(fill
				(thermal_gap 0.5)
				(thermal_bridge_width 0.5)
				(island_removal_mode 0)
			)
			(polygon
				(pts
					(xy 31.214568 -3.067812) (xy 31.214568 -3.575812) (xy 30.833568 -3.575812) (xy 30.833568 -3.067812)
				)
			)
		)
	)
)
